FILE_TYPE = MACRO_DRAWING;
SET COLOR_WIRE YELLOW;
SET COLOR_PROP MONO;
SET COLOR_DOT WHITE;
SET COLOR_ARC YELLOW;
SET COLOR_BODY GREEN;
SET COLOR_NOTE MONO;
SET PROP_DISPLAY VALUE;
SET PAGE_NUMBER P3;
FORCEADD INTEL_CORP_BPAGE..3
(4250 -225);
FORCEPROP 2 LAST CUSTOM_TXT_CDS <XR_PAGE_TITLE>
J 0
(-3640 5025);
DISPLAY 0.638298 (-3640 5025);
PAINT PINK (-3640 5025);
DISPLAY INVISIBLE (-3640 5025);
FORCEPROP 1 LAST CUSTOM_TXT_CDS <CON_TC_SNM56>
J 0
(-300 2800);
PAINT ORANGE (-300 2800);
FORCEPROP 1 LAST CUSTOM_TXT_CDS <CON_TC_SNO6>
J 2
(-2900 3800);
PAINT ORANGE (-2900 3800);
FORCEPROP 1 LAST CUSTOM_TXT_CDS <CON_TC_SNO7>
J 2
(-2900 3700);
PAINT ORANGE (-2900 3700);
FORCEPROP 1 LAST CUSTOM_TXT_CDS <CON_TC_SNM8>
J 0
(-2800 3600);
PAINT ORANGE (-2800 3600);
FORCEPROP 1 LAST CUSTOM_TXT_CDS <CON_TC_SNM1>
J 0
(-2800 4300);
PAINT ORANGE (-2800 4300);
FORCEPROP 1 LAST CUSTOM_TXT_CDS <CON_TC_SNM3>
J 0
(-2800 4100);
PAINT ORANGE (-2800 4100);
FORCEPROP 1 LAST CUSTOM_TXT_CDS <CON_TC_SNM19>
J 0
(-2800 2500);
PAINT ORANGE (-2800 2500);
FORCEPROP 1 LAST CUSTOM_TXT_CDS <CON_TC_SNM61>
J 0
(-300 2300);
PAINT ORANGE (-300 2300);
FORCEPROP 1 LAST CUSTOM_TXT_CDS <CON_TC_SNO38>
J 2
(-2900 600);
PAINT ORANGE (-2900 600);
FORCEPROP 1 LAST CUSTOM_TXT_CDS <CON_TC_SNM32>
J 0
(-2800 1200);
PAINT ORANGE (-2800 1200);
FORCEPROP 1 LAST CUSTOM_TXT_CDS <CON_TC_SNM27>
J 0
(-2800 1700);
PAINT ORANGE (-2800 1700);
FORCEPROP 1 LAST CUSTOM_TXT_CDS <CON_TC_SNM21>
J 0
(-2800 2300);
PAINT ORANGE (-2800 2300);
FORCEPROP 1 LAST CUSTOM_TXT_CDS <CON_TC_SNM17>
J 0
(-2800 2700);
PAINT ORANGE (-2800 2700);
FORCEPROP 1 LAST CUSTOM_TXT_CDS <CON_TC_SNM10>
J 0
(-2800 3400);
PAINT ORANGE (-2800 3400);
FORCEPROP 1 LAST CUSTOM_TXT_CDS <CON_TC_SNO37>
J 2
(-2900 700);
PAINT ORANGE (-2900 700);
FORCEPROP 1 LAST CUSTOM_TXT_CDS <CON_TC_SNO120>
J 2
(2100 400);
PAINT ORANGE (2100 400);
FORCEPROP 1 LAST CUSTOM_TXT_CDS <CON_TC_SNO119>
J 2
(2100 500);
PAINT ORANGE (2100 500);
FORCEPROP 1 LAST CUSTOM_TXT_CDS <CON_TC_SNO118>
J 2
(2100 600);
PAINT ORANGE (2100 600);
FORCEPROP 1 LAST CUSTOM_TXT_CDS <CON_TC_SNO117>
J 2
(2100 700);
PAINT ORANGE (2100 700);
FORCEPROP 1 LAST CUSTOM_TXT_CDS <CON_TC_SNO116>
J 2
(2100 800);
PAINT ORANGE (2100 800);
FORCEPROP 1 LAST CUSTOM_TXT_CDS <CON_TC_SNO115>
J 2
(2100 900);
PAINT ORANGE (2100 900);
FORCEPROP 1 LAST CUSTOM_TXT_CDS <CON_TC_SNO114>
J 2
(2100 1000);
PAINT ORANGE (2100 1000);
FORCEPROP 1 LAST CUSTOM_TXT_CDS <CON_TC_SNO113>
J 2
(2100 1100);
PAINT ORANGE (2100 1100);
FORCEPROP 1 LAST CUSTOM_TXT_CDS <CON_TC_SNO112>
J 2
(2100 1200);
PAINT ORANGE (2100 1200);
FORCEPROP 1 LAST CUSTOM_TXT_CDS <CON_TC_SNO111>
J 2
(2100 1300);
PAINT ORANGE (2100 1300);
FORCEPROP 1 LAST CUSTOM_TXT_CDS <CON_TC_SNO110>
J 2
(2100 1400);
PAINT ORANGE (2100 1400);
FORCEPROP 1 LAST CUSTOM_TXT_CDS <CON_TC_SNO109>
J 2
(2100 1500);
PAINT ORANGE (2100 1500);
FORCEPROP 1 LAST CUSTOM_TXT_CDS <CON_TC_SNO108>
J 2
(2100 1600);
PAINT ORANGE (2100 1600);
FORCEPROP 1 LAST CUSTOM_TXT_CDS <CON_TC_SNO107>
J 2
(2100 1700);
PAINT ORANGE (2100 1700);
FORCEPROP 1 LAST CUSTOM_TXT_CDS <CON_TC_SNO106>
J 2
(2100 1800);
PAINT ORANGE (2100 1800);
FORCEPROP 1 LAST CUSTOM_TXT_CDS <CON_TC_SNO105>
J 2
(2100 1900);
PAINT ORANGE (2100 1900);
FORCEPROP 1 LAST CUSTOM_TXT_CDS <CON_TC_SNO104>
J 2
(2100 2000);
PAINT ORANGE (2100 2000);
FORCEPROP 1 LAST CUSTOM_TXT_CDS <CON_TC_SNO103>
J 2
(2100 2100);
PAINT ORANGE (2100 2100);
FORCEPROP 1 LAST CUSTOM_TXT_CDS <CON_TC_SNO102>
J 2
(2100 2200);
PAINT ORANGE (2100 2200);
FORCEPROP 1 LAST CUSTOM_TXT_CDS <CON_TC_SNO101>
J 2
(2100 2300);
PAINT ORANGE (2100 2300);
FORCEPROP 1 LAST CUSTOM_TXT_CDS <CON_TC_SNO100>
J 2
(2100 2400);
PAINT ORANGE (2100 2400);
FORCEPROP 1 LAST CUSTOM_TXT_CDS <CON_TC_SNO99>
J 2
(2100 2500);
PAINT ORANGE (2100 2500);
FORCEPROP 1 LAST CUSTOM_TXT_CDS <CON_TC_SNO98>
J 2
(2100 2600);
PAINT ORANGE (2100 2600);
FORCEPROP 1 LAST CUSTOM_TXT_CDS <CON_TC_SNO97>
J 2
(2100 2700);
PAINT ORANGE (2100 2700);
FORCEPROP 1 LAST CUSTOM_TXT_CDS <CON_TC_SNO96>
J 2
(2100 2800);
PAINT ORANGE (2100 2800);
FORCEPROP 1 LAST CUSTOM_TXT_CDS <CON_TC_SNO95>
J 2
(2100 2900);
PAINT ORANGE (2100 2900);
FORCEPROP 1 LAST CUSTOM_TXT_CDS <CON_TC_SNO94>
J 2
(2100 3000);
PAINT ORANGE (2100 3000);
FORCEPROP 1 LAST CUSTOM_TXT_CDS <CON_TC_SNO93>
J 2
(2100 3100);
PAINT ORANGE (2100 3100);
FORCEPROP 1 LAST CUSTOM_TXT_CDS <CON_TC_SNO92>
J 2
(2100 3200);
PAINT ORANGE (2100 3200);
FORCEPROP 1 LAST CUSTOM_TXT_CDS <CON_TC_SNO91>
J 2
(2100 3300);
PAINT ORANGE (2100 3300);
FORCEPROP 1 LAST CUSTOM_TXT_CDS <CON_TC_SNO90>
J 2
(2100 3400);
PAINT ORANGE (2100 3400);
FORCEPROP 1 LAST CUSTOM_TXT_CDS <CON_TC_SNO89>
J 2
(2100 3500);
PAINT ORANGE (2100 3500);
FORCEPROP 1 LAST CUSTOM_TXT_CDS <CON_TC_SNO88>
J 2
(2100 3600);
PAINT ORANGE (2100 3600);
FORCEPROP 1 LAST CUSTOM_TXT_CDS <CON_TC_SNO87>
J 2
(2100 3700);
PAINT ORANGE (2100 3700);
FORCEPROP 1 LAST CUSTOM_TXT_CDS <CON_TC_SNO86>
J 2
(2100 3800);
PAINT ORANGE (2100 3800);
FORCEPROP 1 LAST CUSTOM_TXT_CDS <CON_TC_SNO85>
J 2
(2100 3900);
PAINT ORANGE (2100 3900);
FORCEPROP 1 LAST CUSTOM_TXT_CDS <CON_TC_SNO84>
J 2
(2100 4000);
PAINT ORANGE (2100 4000);
FORCEPROP 1 LAST CUSTOM_TXT_CDS <CON_TC_SNO83>
J 2
(2100 4100);
PAINT ORANGE (2100 4100);
FORCEPROP 1 LAST CUSTOM_TXT_CDS <CON_TC_SNO82>
J 2
(2100 4200);
PAINT ORANGE (2100 4200);
FORCEPROP 1 LAST CUSTOM_TXT_CDS <CON_TC_SNO81>
J 2
(2100 4300);
PAINT ORANGE (2100 4300);
FORCEPROP 1 LAST CUSTOM_TXT_CDS <CON_TC_SNO80>
J 2
(-400 400);
PAINT ORANGE (-400 400);
FORCEPROP 1 LAST CUSTOM_TXT_CDS <CON_TC_SNO79>
J 2
(-400 500);
PAINT ORANGE (-400 500);
FORCEPROP 1 LAST CUSTOM_TXT_CDS <CON_TC_SNO78>
J 2
(-400 600);
PAINT ORANGE (-400 600);
FORCEPROP 1 LAST CUSTOM_TXT_CDS <CON_TC_SNO77>
J 2
(-400 700);
PAINT ORANGE (-400 700);
FORCEPROP 1 LAST CUSTOM_TXT_CDS <CON_TC_SNO76>
J 2
(-400 800);
PAINT ORANGE (-400 800);
FORCEPROP 1 LAST CUSTOM_TXT_CDS <CON_TC_SNO75>
J 2
(-400 900);
PAINT ORANGE (-400 900);
FORCEPROP 1 LAST CUSTOM_TXT_CDS <CON_TC_SNO74>
J 2
(-400 1000);
PAINT ORANGE (-400 1000);
FORCEPROP 1 LAST CUSTOM_TXT_CDS <CON_TC_SNO73>
J 2
(-400 1100);
PAINT ORANGE (-400 1100);
FORCEPROP 1 LAST CUSTOM_TXT_CDS <CON_TC_SNO72>
J 2
(-400 1200);
PAINT ORANGE (-400 1200);
FORCEPROP 1 LAST CUSTOM_TXT_CDS <CON_TC_SNO71>
J 2
(-400 1300);
PAINT ORANGE (-400 1300);
FORCEPROP 1 LAST CUSTOM_TXT_CDS <CON_TC_SNO70>
J 2
(-400 1400);
PAINT ORANGE (-400 1400);
FORCEPROP 1 LAST CUSTOM_TXT_CDS <CON_TC_SNO69>
J 2
(-400 1500);
PAINT ORANGE (-400 1500);
FORCEPROP 1 LAST CUSTOM_TXT_CDS <CON_TC_SNO68>
J 2
(-400 1600);
PAINT ORANGE (-400 1600);
FORCEPROP 1 LAST CUSTOM_TXT_CDS <CON_TC_SNO67>
J 2
(-400 1700);
PAINT ORANGE (-400 1700);
FORCEPROP 1 LAST CUSTOM_TXT_CDS <CON_TC_SNO66>
J 2
(-400 1800);
PAINT ORANGE (-400 1800);
FORCEPROP 1 LAST CUSTOM_TXT_CDS <CON_TC_SNO65>
J 2
(-400 1900);
PAINT ORANGE (-400 1900);
FORCEPROP 1 LAST CUSTOM_TXT_CDS <CON_TC_SNO64>
J 2
(-400 2000);
PAINT ORANGE (-400 2000);
FORCEPROP 1 LAST CUSTOM_TXT_CDS <CON_TC_SNO63>
J 2
(-400 2100);
PAINT ORANGE (-400 2100);
FORCEPROP 1 LAST CUSTOM_TXT_CDS <CON_TC_SNO62>
J 2
(-400 2200);
PAINT ORANGE (-400 2200);
FORCEPROP 1 LAST CUSTOM_TXT_CDS <CON_TC_SNO61>
J 2
(-400 2300);
PAINT ORANGE (-400 2300);
FORCEPROP 1 LAST CUSTOM_TXT_CDS <CON_TC_SNO60>
J 2
(-400 2400);
PAINT ORANGE (-400 2400);
FORCEPROP 1 LAST CUSTOM_TXT_CDS <CON_TC_SNO59>
J 2
(-400 2500);
PAINT ORANGE (-400 2500);
FORCEPROP 1 LAST CUSTOM_TXT_CDS <CON_TC_SNO58>
J 2
(-400 2600);
PAINT ORANGE (-400 2600);
FORCEPROP 1 LAST CUSTOM_TXT_CDS <CON_TC_SNO57>
J 2
(-400 2700);
PAINT ORANGE (-400 2700);
FORCEPROP 1 LAST CUSTOM_TXT_CDS <CON_TC_SNO56>
J 2
(-400 2800);
PAINT ORANGE (-400 2800);
FORCEPROP 1 LAST CUSTOM_TXT_CDS <CON_TC_SNO55>
J 2
(-400 2900);
PAINT ORANGE (-400 2900);
FORCEPROP 1 LAST CUSTOM_TXT_CDS <CON_TC_SNO54>
J 2
(-400 3000);
PAINT ORANGE (-400 3000);
FORCEPROP 1 LAST CUSTOM_TXT_CDS <CON_TC_SNO53>
J 2
(-400 3100);
PAINT ORANGE (-400 3100);
FORCEPROP 1 LAST CUSTOM_TXT_CDS <CON_TC_SNO52>
J 2
(-400 3200);
PAINT ORANGE (-400 3200);
FORCEPROP 1 LAST CUSTOM_TXT_CDS <CON_TC_SNO51>
J 2
(-400 3300);
PAINT ORANGE (-400 3300);
FORCEPROP 1 LAST CUSTOM_TXT_CDS <CON_TC_SNO50>
J 2
(-400 3400);
PAINT ORANGE (-400 3400);
FORCEPROP 1 LAST CUSTOM_TXT_CDS <CON_TC_SNO49>
J 2
(-400 3500);
PAINT ORANGE (-400 3500);
FORCEPROP 1 LAST CUSTOM_TXT_CDS <CON_TC_SNO48>
J 2
(-400 3600);
PAINT ORANGE (-400 3600);
FORCEPROP 1 LAST CUSTOM_TXT_CDS <CON_TC_SNO47>
J 2
(-400 3700);
PAINT ORANGE (-400 3700);
FORCEPROP 1 LAST CUSTOM_TXT_CDS <CON_TC_SNO46>
J 2
(-400 3800);
PAINT ORANGE (-400 3800);
FORCEPROP 1 LAST CUSTOM_TXT_CDS <CON_TC_SNO45>
J 2
(-400 3900);
PAINT ORANGE (-400 3900);
FORCEPROP 1 LAST CUSTOM_TXT_CDS <CON_TC_SNO44>
J 2
(-400 4000);
PAINT ORANGE (-400 4000);
FORCEPROP 1 LAST CUSTOM_TXT_CDS <CON_TC_SNO43>
J 2
(-400 4100);
PAINT ORANGE (-400 4100);
FORCEPROP 1 LAST CUSTOM_TXT_CDS <CON_TC_SNO42>
J 2
(-400 4200);
PAINT ORANGE (-400 4200);
FORCEPROP 1 LAST CUSTOM_TXT_CDS <CON_TC_SNO41>
J 2
(-400 4300);
PAINT ORANGE (-400 4300);
FORCEPROP 1 LAST CUSTOM_TXT_CDS <CON_TC_SNO40>
J 2
(-2900 400);
PAINT ORANGE (-2900 400);
FORCEPROP 1 LAST CUSTOM_TXT_CDS <CON_TC_SNO39>
J 2
(-2900 500);
PAINT ORANGE (-2900 500);
FORCEPROP 1 LAST CUSTOM_TXT_CDS <CON_TC_SNO36>
J 2
(-2900 800);
PAINT ORANGE (-2900 800);
FORCEPROP 1 LAST CUSTOM_TXT_CDS <CON_TC_SNO35>
J 2
(-2900 900);
PAINT ORANGE (-2900 900);
FORCEPROP 1 LAST CUSTOM_TXT_CDS <CON_TC_SNO34>
J 2
(-2900 1000);
PAINT ORANGE (-2900 1000);
FORCEPROP 1 LAST CUSTOM_TXT_CDS <CON_TC_SNO33>
J 2
(-2900 1100);
PAINT ORANGE (-2900 1100);
FORCEPROP 1 LAST CUSTOM_TXT_CDS <CON_TC_SNO32>
J 2
(-2900 1200);
PAINT ORANGE (-2900 1200);
FORCEPROP 1 LAST CUSTOM_TXT_CDS <CON_TC_SNO31>
J 2
(-2900 1300);
PAINT ORANGE (-2900 1300);
FORCEPROP 1 LAST CUSTOM_TXT_CDS <CON_TC_SNO30>
J 2
(-2900 1400);
PAINT ORANGE (-2900 1400);
FORCEPROP 1 LAST CUSTOM_TXT_CDS <CON_TC_SNO29>
J 2
(-2900 1500);
PAINT ORANGE (-2900 1500);
FORCEPROP 1 LAST CUSTOM_TXT_CDS <CON_TC_SNO28>
J 2
(-2900 1600);
PAINT ORANGE (-2900 1600);
FORCEPROP 1 LAST CUSTOM_TXT_CDS <CON_TC_SNO27>
J 2
(-2900 1700);
PAINT ORANGE (-2900 1700);
FORCEPROP 1 LAST CUSTOM_TXT_CDS <CON_TC_SNO26>
J 2
(-2900 1800);
PAINT ORANGE (-2900 1800);
FORCEPROP 1 LAST CUSTOM_TXT_CDS <CON_TC_SNO25>
J 2
(-2900 1900);
PAINT ORANGE (-2900 1900);
FORCEPROP 1 LAST CUSTOM_TXT_CDS <CON_TC_SNO24>
J 2
(-2900 2000);
PAINT ORANGE (-2900 2000);
FORCEPROP 1 LAST CUSTOM_TXT_CDS <CON_TC_SNO23>
J 2
(-2900 2100);
PAINT ORANGE (-2900 2100);
FORCEPROP 1 LAST CUSTOM_TXT_CDS <CON_TC_SNO22>
J 2
(-2900 2200);
PAINT ORANGE (-2900 2200);
FORCEPROP 1 LAST CUSTOM_TXT_CDS <CON_TC_SNO21>
J 2
(-2900 2300);
PAINT ORANGE (-2900 2300);
FORCEPROP 1 LAST CUSTOM_TXT_CDS <CON_TC_SNO20>
J 2
(-2900 2400);
PAINT ORANGE (-2900 2400);
FORCEPROP 1 LAST CUSTOM_TXT_CDS <CON_TC_SNO19>
J 2
(-2900 2500);
PAINT ORANGE (-2900 2500);
FORCEPROP 1 LAST CUSTOM_TXT_CDS <CON_TC_SNO18>
J 2
(-2900 2600);
PAINT ORANGE (-2900 2600);
FORCEPROP 1 LAST CUSTOM_TXT_CDS <CON_TC_SNO17>
J 2
(-2900 2700);
PAINT ORANGE (-2900 2700);
FORCEPROP 1 LAST CUSTOM_TXT_CDS <CON_TC_SNO16>
J 2
(-2900 2800);
PAINT ORANGE (-2900 2800);
FORCEPROP 1 LAST CUSTOM_TXT_CDS <CON_TC_SNO15>
J 2
(-2900 2900);
PAINT ORANGE (-2900 2900);
FORCEPROP 1 LAST CUSTOM_TXT_CDS <CON_TC_SNO14>
J 2
(-2900 3000);
PAINT ORANGE (-2900 3000);
FORCEPROP 1 LAST CUSTOM_TXT_CDS <CON_TC_SNO13>
J 2
(-2900 3100);
PAINT ORANGE (-2900 3100);
FORCEPROP 1 LAST CUSTOM_TXT_CDS <CON_TC_SNO12>
J 2
(-2900 3200);
PAINT ORANGE (-2900 3200);
FORCEPROP 1 LAST CUSTOM_TXT_CDS <CON_TC_SNO11>
J 2
(-2900 3300);
PAINT ORANGE (-2900 3300);
FORCEPROP 1 LAST CUSTOM_TXT_CDS <CON_TC_SNO10>
J 2
(-2900 3400);
PAINT ORANGE (-2900 3400);
FORCEPROP 1 LAST CUSTOM_TXT_CDS <CON_TC_SNO9>
J 2
(-2900 3500);
PAINT ORANGE (-2900 3500);
FORCEPROP 1 LAST CUSTOM_TXT_CDS <CON_TC_SNO8>
J 2
(-2900 3600);
PAINT ORANGE (-2900 3600);
FORCEPROP 1 LAST CUSTOM_TXT_CDS <CON_TC_SNO5>
J 2
(-2900 3900);
PAINT ORANGE (-2900 3900);
FORCEPROP 1 LAST CUSTOM_TXT_CDS <CON_TC_SNO4>
J 2
(-2900 4000);
PAINT ORANGE (-2900 4000);
FORCEPROP 1 LAST CUSTOM_TXT_CDS <CON_TC_SNO3>
J 2
(-2900 4100);
PAINT ORANGE (-2900 4100);
FORCEPROP 1 LAST CUSTOM_TXT_CDS <CON_TC_SNO2>
J 2
(-2900 4200);
PAINT ORANGE (-2900 4200);
FORCEPROP 1 LAST CUSTOM_TXT_CDS <CON_TC_SNO1>
J 2
(-2900 4300);
PAINT ORANGE (-2900 4300);
FORCEPROP 1 LAST CUSTOM_TXT_CDS <CON_TC_SNM120>
J 0
(2200 400);
PAINT ORANGE (2200 400);
FORCEPROP 1 LAST CUSTOM_TXT_CDS <CON_TC_SNM119>
J 0
(2200 500);
PAINT ORANGE (2200 500);
FORCEPROP 1 LAST CUSTOM_TXT_CDS <CON_TC_SNM118>
J 0
(2200 600);
PAINT ORANGE (2200 600);
FORCEPROP 1 LAST CUSTOM_TXT_CDS <CON_TC_SNM117>
J 0
(2200 700);
PAINT ORANGE (2200 700);
FORCEPROP 1 LAST CUSTOM_TXT_CDS <CON_TC_SNM116>
J 0
(2200 800);
PAINT ORANGE (2200 800);
FORCEPROP 1 LAST CUSTOM_TXT_CDS <CON_TC_SNM115>
J 0
(2200 900);
PAINT ORANGE (2200 900);
FORCEPROP 1 LAST CUSTOM_TXT_CDS <CON_TC_SNM114>
J 0
(2200 1000);
PAINT ORANGE (2200 1000);
FORCEPROP 1 LAST CUSTOM_TXT_CDS <CON_TC_SNM113>
J 0
(2200 1100);
PAINT ORANGE (2200 1100);
FORCEPROP 1 LAST CUSTOM_TXT_CDS <CON_TC_SNM112>
J 0
(2200 1200);
PAINT ORANGE (2200 1200);
FORCEPROP 1 LAST CUSTOM_TXT_CDS <CON_TC_SNM111>
J 0
(2200 1300);
PAINT ORANGE (2200 1300);
FORCEPROP 1 LAST CUSTOM_TXT_CDS <CON_TC_SNM110>
J 0
(2200 1400);
PAINT ORANGE (2200 1400);
FORCEPROP 1 LAST CUSTOM_TXT_CDS <CON_TC_SNM109>
J 0
(2200 1500);
PAINT ORANGE (2200 1500);
FORCEPROP 1 LAST CUSTOM_TXT_CDS <CON_TC_SNM108>
J 0
(2200 1600);
PAINT ORANGE (2200 1600);
FORCEPROP 1 LAST CUSTOM_TXT_CDS <CON_TC_SNM107>
J 0
(2200 1700);
PAINT ORANGE (2200 1700);
FORCEPROP 1 LAST CUSTOM_TXT_CDS <CON_TC_SNM106>
J 0
(2200 1800);
PAINT ORANGE (2200 1800);
FORCEPROP 1 LAST CUSTOM_TXT_CDS <CON_TC_SNM105>
J 0
(2200 1900);
PAINT ORANGE (2200 1900);
FORCEPROP 1 LAST CUSTOM_TXT_CDS <CON_TC_SNM104>
J 0
(2200 2000);
PAINT ORANGE (2200 2000);
FORCEPROP 1 LAST CUSTOM_TXT_CDS <CON_TC_SNM103>
J 0
(2200 2100);
PAINT ORANGE (2200 2100);
FORCEPROP 1 LAST CUSTOM_TXT_CDS <CON_TC_SNM102>
J 0
(2200 2200);
PAINT ORANGE (2200 2200);
FORCEPROP 1 LAST CUSTOM_TXT_CDS <CON_TC_SNM101>
J 0
(2200 2300);
PAINT ORANGE (2200 2300);
FORCEPROP 1 LAST CUSTOM_TXT_CDS <CON_TC_SNM100>
J 0
(2200 2400);
PAINT ORANGE (2200 2400);
FORCEPROP 1 LAST CUSTOM_TXT_CDS <CON_TC_SNM99>
J 0
(2200 2500);
PAINT ORANGE (2200 2500);
FORCEPROP 1 LAST CUSTOM_TXT_CDS <CON_TC_SNM98>
J 0
(2200 2600);
PAINT ORANGE (2200 2600);
FORCEPROP 1 LAST CUSTOM_TXT_CDS <CON_TC_SNM97>
J 0
(2200 2700);
PAINT ORANGE (2200 2700);
FORCEPROP 1 LAST CUSTOM_TXT_CDS <CON_TC_SNM96>
J 0
(2200 2800);
PAINT ORANGE (2200 2800);
FORCEPROP 1 LAST CUSTOM_TXT_CDS <CON_TC_SNM95>
J 0
(2200 2900);
PAINT ORANGE (2200 2900);
FORCEPROP 1 LAST CUSTOM_TXT_CDS <CON_TC_SNM94>
J 0
(2200 3000);
PAINT ORANGE (2200 3000);
FORCEPROP 1 LAST CUSTOM_TXT_CDS <CON_TC_SNM93>
J 0
(2200 3100);
PAINT ORANGE (2200 3100);
FORCEPROP 1 LAST CUSTOM_TXT_CDS <CON_TC_SNM92>
J 0
(2200 3200);
PAINT ORANGE (2200 3200);
FORCEPROP 1 LAST CUSTOM_TXT_CDS <CON_TC_SNM91>
J 0
(2200 3300);
PAINT ORANGE (2200 3300);
FORCEPROP 1 LAST CUSTOM_TXT_CDS <CON_TC_SNM90>
J 0
(2200 3400);
PAINT ORANGE (2200 3400);
FORCEPROP 1 LAST CUSTOM_TXT_CDS <CON_TC_SNM89>
J 0
(2200 3500);
PAINT ORANGE (2200 3500);
FORCEPROP 1 LAST CUSTOM_TXT_CDS <CON_TC_SNM88>
J 0
(2200 3600);
PAINT ORANGE (2200 3600);
FORCEPROP 1 LAST CUSTOM_TXT_CDS <CON_TC_SNM87>
J 0
(2200 3700);
PAINT ORANGE (2200 3700);
FORCEPROP 1 LAST CUSTOM_TXT_CDS <CON_TC_SNM86>
J 0
(2200 3800);
PAINT ORANGE (2200 3800);
FORCEPROP 1 LAST CUSTOM_TXT_CDS <CON_TC_SNM85>
J 0
(2200 3900);
PAINT ORANGE (2200 3900);
FORCEPROP 1 LAST CUSTOM_TXT_CDS <CON_TC_SNM84>
J 0
(2200 4000);
PAINT ORANGE (2200 4000);
FORCEPROP 1 LAST CUSTOM_TXT_CDS <CON_TC_SNM83>
J 0
(2200 4100);
PAINT ORANGE (2200 4100);
FORCEPROP 1 LAST CUSTOM_TXT_CDS <CON_TC_SNM82>
J 0
(2200 4200);
PAINT ORANGE (2200 4200);
FORCEPROP 1 LAST CUSTOM_TXT_CDS <CON_TC_SNM81>
J 0
(2200 4300);
PAINT ORANGE (2200 4300);
FORCEPROP 1 LAST CUSTOM_TXT_CDS <CON_TC_SNM80>
J 0
(-300 400);
PAINT ORANGE (-300 400);
FORCEPROP 1 LAST CUSTOM_TXT_CDS <CON_TC_SNM79>
J 0
(-300 500);
PAINT ORANGE (-300 500);
FORCEPROP 1 LAST CUSTOM_TXT_CDS <CON_TC_SNM78>
J 0
(-300 600);
PAINT ORANGE (-300 600);
FORCEPROP 1 LAST CUSTOM_TXT_CDS <CON_TC_SNM77>
J 0
(-300 700);
PAINT ORANGE (-300 700);
FORCEPROP 1 LAST CUSTOM_TXT_CDS <CON_TC_SNM76>
J 0
(-300 800);
PAINT ORANGE (-300 800);
FORCEPROP 1 LAST CUSTOM_TXT_CDS <CON_TC_SNM75>
J 0
(-300 900);
PAINT ORANGE (-300 900);
FORCEPROP 1 LAST CUSTOM_TXT_CDS <CON_TC_SNM74>
J 0
(-300 1000);
PAINT ORANGE (-300 1000);
FORCEPROP 1 LAST CUSTOM_TXT_CDS <CON_TC_SNM73>
J 0
(-300 1100);
PAINT ORANGE (-300 1100);
FORCEPROP 1 LAST CUSTOM_TXT_CDS <CON_TC_SNM72>
J 0
(-300 1200);
PAINT ORANGE (-300 1200);
FORCEPROP 1 LAST CUSTOM_TXT_CDS <CON_TC_SNM71>
J 0
(-300 1300);
PAINT ORANGE (-300 1300);
FORCEPROP 1 LAST CUSTOM_TXT_CDS <CON_TC_SNM70>
J 0
(-300 1400);
PAINT ORANGE (-300 1400);
FORCEPROP 1 LAST CUSTOM_TXT_CDS <CON_TC_SNM69>
J 0
(-300 1500);
PAINT ORANGE (-300 1500);
FORCEPROP 1 LAST CUSTOM_TXT_CDS <CON_TC_SNM68>
J 0
(-300 1600);
PAINT ORANGE (-300 1600);
FORCEPROP 1 LAST CUSTOM_TXT_CDS <CON_TC_SNM67>
J 0
(-300 1700);
PAINT ORANGE (-300 1700);
FORCEPROP 1 LAST CUSTOM_TXT_CDS <CON_TC_SNM66>
J 0
(-300 1800);
PAINT ORANGE (-300 1800);
FORCEPROP 1 LAST CUSTOM_TXT_CDS <CON_TC_SNM65>
J 0
(-300 1900);
PAINT ORANGE (-300 1900);
FORCEPROP 1 LAST CUSTOM_TXT_CDS <CON_TC_SNM64>
J 0
(-300 2000);
PAINT ORANGE (-300 2000);
FORCEPROP 1 LAST CUSTOM_TXT_CDS <CON_TC_SNM63>
J 0
(-300 2100);
PAINT ORANGE (-300 2100);
FORCEPROP 1 LAST CUSTOM_TXT_CDS <CON_TC_SNM62>
J 0
(-300 2200);
PAINT ORANGE (-300 2200);
FORCEPROP 1 LAST CUSTOM_TXT_CDS <CON_TC_SNM60>
J 0
(-300 2400);
PAINT ORANGE (-300 2400);
FORCEPROP 1 LAST CUSTOM_TXT_CDS <CON_TC_SNM59>
J 0
(-300 2500);
PAINT ORANGE (-300 2500);
FORCEPROP 1 LAST CUSTOM_TXT_CDS <CON_TC_SNM58>
J 0
(-300 2600);
PAINT ORANGE (-300 2600);
FORCEPROP 1 LAST CUSTOM_TXT_CDS <CON_TC_SNM57>
J 0
(-300 2700);
PAINT ORANGE (-300 2700);
FORCEPROP 1 LAST CUSTOM_TXT_CDS <CON_TC_SNM55>
J 0
(-300 2900);
PAINT ORANGE (-300 2900);
FORCEPROP 1 LAST CUSTOM_TXT_CDS <CON_TC_SNM54>
J 0
(-300 3000);
PAINT ORANGE (-300 3000);
FORCEPROP 1 LAST CUSTOM_TXT_CDS <CON_TC_SNM53>
J 0
(-300 3100);
PAINT ORANGE (-300 3100);
FORCEPROP 1 LAST CUSTOM_TXT_CDS <CON_TC_SNM52>
J 0
(-300 3200);
PAINT ORANGE (-300 3200);
FORCEPROP 1 LAST CUSTOM_TXT_CDS <CON_TC_SNM51>
J 0
(-300 3300);
PAINT ORANGE (-300 3300);
FORCEPROP 1 LAST CUSTOM_TXT_CDS <CON_TC_SNM50>
J 0
(-300 3400);
PAINT ORANGE (-300 3400);
FORCEPROP 1 LAST CUSTOM_TXT_CDS <CON_TC_SNM49>
J 0
(-300 3500);
PAINT ORANGE (-300 3500);
FORCEPROP 1 LAST CUSTOM_TXT_CDS <CON_TC_SNM48>
J 0
(-300 3600);
PAINT ORANGE (-300 3600);
FORCEPROP 1 LAST CUSTOM_TXT_CDS <CON_TC_SNM47>
J 0
(-300 3700);
PAINT ORANGE (-300 3700);
FORCEPROP 1 LAST CUSTOM_TXT_CDS <CON_TC_SNM46>
J 0
(-300 3800);
PAINT ORANGE (-300 3800);
FORCEPROP 1 LAST CUSTOM_TXT_CDS <CON_TC_SNM45>
J 0
(-300 3900);
PAINT ORANGE (-300 3900);
FORCEPROP 1 LAST CUSTOM_TXT_CDS <CON_TC_SNM44>
J 0
(-300 4000);
PAINT ORANGE (-300 4000);
FORCEPROP 1 LAST CUSTOM_TXT_CDS <CON_TC_SNM43>
J 0
(-300 4100);
PAINT ORANGE (-300 4100);
FORCEPROP 1 LAST CUSTOM_TXT_CDS <CON_TC_SNM42>
J 0
(-300 4200);
PAINT ORANGE (-300 4200);
FORCEPROP 1 LAST CUSTOM_TXT_CDS <CON_TC_SNM41>
J 0
(-300 4300);
PAINT ORANGE (-300 4300);
FORCEPROP 1 LAST CUSTOM_TXT_CDS <CON_TC_SNM40>
J 0
(-2800 400);
PAINT ORANGE (-2800 400);
FORCEPROP 1 LAST CUSTOM_TXT_CDS <CON_TC_SNM39>
J 0
(-2800 500);
PAINT ORANGE (-2800 500);
FORCEPROP 1 LAST CUSTOM_TXT_CDS <CON_TC_SNM38>
J 0
(-2800 600);
PAINT ORANGE (-2800 600);
FORCEPROP 1 LAST CUSTOM_TXT_CDS <CON_TC_SNM37>
J 0
(-2800 700);
PAINT ORANGE (-2800 700);
FORCEPROP 1 LAST CUSTOM_TXT_CDS <CON_TC_SNM36>
J 0
(-2800 800);
PAINT ORANGE (-2800 800);
FORCEPROP 1 LAST CUSTOM_TXT_CDS <CON_TC_SNM35>
J 0
(-2800 900);
PAINT ORANGE (-2800 900);
FORCEPROP 1 LAST CUSTOM_TXT_CDS <CON_TC_SNM34>
J 0
(-2800 1000);
PAINT ORANGE (-2800 1000);
FORCEPROP 1 LAST CUSTOM_TXT_CDS <CON_TC_SNM33>
J 0
(-2800 1100);
PAINT ORANGE (-2800 1100);
FORCEPROP 1 LAST CUSTOM_TXT_CDS <CON_TC_SNM31>
J 0
(-2800 1300);
PAINT ORANGE (-2800 1300);
FORCEPROP 1 LAST CUSTOM_TXT_CDS <CON_TC_SNM30>
J 0
(-2800 1400);
PAINT ORANGE (-2800 1400);
FORCEPROP 1 LAST CUSTOM_TXT_CDS <CON_TC_SNM29>
J 0
(-2800 1500);
PAINT ORANGE (-2800 1500);
FORCEPROP 1 LAST CUSTOM_TXT_CDS <CON_TC_SNM28>
J 0
(-2800 1600);
PAINT ORANGE (-2800 1600);
FORCEPROP 1 LAST CUSTOM_TXT_CDS <CON_TC_SNM26>
J 0
(-2800 1800);
PAINT ORANGE (-2800 1800);
FORCEPROP 1 LAST CUSTOM_TXT_CDS <CON_TC_SNM25>
J 0
(-2800 1900);
PAINT ORANGE (-2800 1900);
FORCEPROP 1 LAST CUSTOM_TXT_CDS <CON_TC_SNM24>
J 0
(-2800 2000);
PAINT ORANGE (-2800 2000);
FORCEPROP 1 LAST CUSTOM_TXT_CDS <CON_TC_SNM23>
J 0
(-2800 2100);
PAINT ORANGE (-2800 2100);
FORCEPROP 1 LAST CUSTOM_TXT_CDS <CON_TC_SNM22>
J 0
(-2800 2200);
PAINT ORANGE (-2800 2200);
FORCEPROP 1 LAST CUSTOM_TXT_CDS <CON_TC_SNM20>
J 0
(-2800 2400);
PAINT ORANGE (-2800 2400);
FORCEPROP 1 LAST CUSTOM_TXT_CDS <CON_TC_SNM18>
J 0
(-2800 2600);
PAINT ORANGE (-2800 2600);
FORCEPROP 1 LAST CUSTOM_TXT_CDS <CON_TC_SNM16>
J 0
(-2800 2800);
PAINT ORANGE (-2800 2800);
FORCEPROP 1 LAST CUSTOM_TXT_CDS <CON_TC_SNM15>
J 0
(-2800 2900);
PAINT ORANGE (-2800 2900);
FORCEPROP 1 LAST CUSTOM_TXT_CDS <CON_TC_SNM14>
J 0
(-2800 3000);
PAINT ORANGE (-2800 3000);
FORCEPROP 1 LAST CUSTOM_TXT_CDS <CON_TC_SNM13>
J 0
(-2800 3100);
PAINT ORANGE (-2800 3100);
FORCEPROP 1 LAST CUSTOM_TXT_CDS <CON_TC_SNM12>
J 0
(-2800 3200);
PAINT ORANGE (-2800 3200);
FORCEPROP 1 LAST CUSTOM_TXT_CDS <CON_TC_SNM11>
J 0
(-2800 3300);
PAINT ORANGE (-2800 3300);
FORCEPROP 1 LAST CUSTOM_TXT_CDS <CON_TC_SNM9>
J 0
(-2800 3500);
PAINT ORANGE (-2800 3500);
FORCEPROP 1 LAST CUSTOM_TXT_CDS <CON_TC_SNM7>
J 0
(-2800 3700);
PAINT ORANGE (-2800 3700);
FORCEPROP 1 LAST CUSTOM_TXT_CDS <CON_TC_SNM5>
J 0
(-2800 3900);
PAINT ORANGE (-2800 3900);
FORCEPROP 1 LAST CUSTOM_TXT_CDS <CON_TC_SNM4>
J 0
(-2800 4000);
PAINT ORANGE (-2800 4000);
FORCEPROP 1 LAST CUSTOM_TXT_CDS <CON_TC_SNM2>
J 0
(-2800 4200);
PAINT ORANGE (-2800 4200);
FORCEPROP 1 LAST CUSTOM_TXT_CDS <CON_LAST_MODIFIED>
J 0
(2325 125);
PAINT ORANGE (2325 125);
FORCEPROP 1 LAST CUSTOM_TXT_CDS <CURRENT_DESIGN_SHEET> OF <TOTAL_DESIGN_SHEETS>
J 0
(3750 -200);
PAINT ORANGE (3750 -200);
FORCEPROP 1 LAST CUSTOM_TXT_CDS <CON_TC_SNM6>
J 0
(-2800 3800);
PAINT ORANGE (-2800 3800);
FORCEPROP 1 LAST SCH_ADDRESS3 Santa Clara, CA 95052-8119
J 0
(275 -200);
DISPLAY 0.617021 (275 -200);
PAINT GREEN (275 -200);
FORCEPROP 1 LAST SCH_ADDRESS2 P.O. BOX 58119
J 0
(275 -150);
DISPLAY 0.617021 (275 -150);
PAINT GREEN (275 -150);
FORCEPROP 1 LAST SCH_ADDRESS1 2200 Mission College Blvd.
J 0
(275 -100);
DISPLAY 0.617021 (275 -100);
PAINT GREEN (275 -100);
FORCEPROP 1 LAST SCH_TITLE INDEX (2 OF 3)
J 0
(-3700 -175);
DISPLAY 1.212766 (-3700 -175);
PAINT ORANGE (-3700 -175);
FORCEPROP 2 LAST SCH_NUMBER H4694802
J 0
(2950 -75);
DISPLAY 1.212766 (2950 -75);
PAINT YELLOW (2950 -75);
FORCEPROP 2 LAST SCH_DEPT BESD
J 1
(-200 -125);
DISPLAY 1.212766 (-200 -125);
PAINT YELLOW (-200 -125);
FORCEPROP 2 LAST SCH_REV 2.420
J 0
(4000 -75);
DISPLAY 0.978723 (4000 -75);
PAINT YELLOW (4000 -75);
FORCEPROP 2 LAST PAGE_BORDER TRUE
J 0
(-3640 5025);
DISPLAY 0.638298 (-3640 5025);
PAINT PINK (-3640 5025);
DISPLAY INVISIBLE (-3640 5025);
FORCEPROP 2 LAST CDS_LIB mstr_symbols
J 0
(4250 -225);
PAINT MONO (4250 -225);
DISPLAY INVISIBLE (4250 -225);
FORCEPROP 1 LAST TOC_SYMBOL TRUE
J 0
(-3700 4825);
PAINT ORANGE (-3700 4825);
DISPLAY INVISIBLE (-3700 4825);
FORCEPROP 1 LAST COMMENT_BODY TRUE
J 0
(4262 -213);
DISPLAY 0.468085 (4262 -213);
PAINT GREEN (4262 -213);
DISPLAY INVISIBLE (4262 -213);
FORCEPROP 0 LAST CDS_CON_LAST_MODIFIED Tue Dec 01 11:47:55 2015
J 0
(2325 125);
PAINT MONO (2325 125);
DISPLAY INVISIBLE (2325 125);
FORCEPROP 2 LAST CDS_XR_PAGE_TITLE CR-3 : @BASEBOARD_FAB2_LIB.BASEBOARD_FAB2(SCH_1):PAGE3
J 0
(-3640 5025);
DISPLAY 0.638298 (-3640 5025);
PAINT PINK (-3640 5025);
DISPLAY INVISIBLE (-3640 5025);
QUIT
